(kicad_pcb
	(version 20260206)
	(generator "pcbnew")
	(generator_version "10.0")
	(general
		(thickness 1.6)
		(legacy_teardrops no)
	)
	(paper "A4")
	(title_block
		(title "01162023_DA0F0TEBIF0_F0T_Expander_BD_F_brd_V02_OCP.brd")
		(comment 1 "Grand Teton / footprints 1848-1848 of 9728")
	)
	(layers
		(0 "F.Cu" signal "TOP")
		(4 "In1.Cu" signal "GND")
		(6 "In2.Cu" signal "VCC")
		(8 "In3.Cu" signal "VCC1")
		(10 "In4.Cu" signal "GND1")
		(12 "In5.Cu" signal "IN1")
		(14 "In6.Cu" signal "GND2")
		(16 "In7.Cu" signal "IN2")
		(18 "In8.Cu" signal "GND3")
		(20 "In9.Cu" signal "IN3")
		(22 "In10.Cu" signal "GND4")
		(24 "In11.Cu" signal "IN4")
		(26 "In12.Cu" signal "GND5")
		(28 "In13.Cu" signal "IN5")
		(30 "In14.Cu" signal "GND6")
		(32 "In15.Cu" signal "IN6")
		(34 "In16.Cu" signal "GND7")
		(2 "B.Cu" signal "BOTTOM")
		(9 "F.Adhes" user "F.Adhesive")
		(11 "B.Adhes" user "B.Adhesive")
		(13 "F.Paste" user "Package Geometry/Pastemask Top")
		(15 "B.Paste" user "Package Geometry/Pastemask Bottom")
		(5 "F.SilkS" user "Ref Des/Silkscreen Top")
		(7 "B.SilkS" user "Ref Des/Silkscreen Bottom")
		(1 "F.Mask" user "Board Geometry/Soldermask Top")
		(3 "B.Mask" user "Board Geometry/Soldermask Bottom")
		(17 "Dwgs.User" user "User.Drawings")
		(19 "Cmts.User" user "User.Comments")
		(21 "Eco1.User" user "User.Eco1")
		(23 "Eco2.User" user "User.Eco2")
		(25 "Edge.Cuts" user "Board Geometry/Outline")
		(27 "Margin" user)
		(31 "F.CrtYd" user "Package Geometry/Place Bound Top")
		(29 "B.CrtYd" user "Package Geometry/Place Bound Bottom")
		(35 "F.Fab" user "Ref Des/Assembly Top")
		(33 "B.Fab" user "Ref Des/Assembly Bottom")
	)
	(footprint ""
		(layer "F.Cu")
		(at 350.14027 -32.848042 90)
		(property "Reference" "PC963"
			(at 0 0 90)
			(layer "F.SilkS")
			(hide yes)
			(effects
				(font
					(size 1.27 1.27)
				)
			)
		)
		(property "Value" ""
			(at 0 0 90)
			(layer "F.Fab")
			(effects
				(font
					(size 1.27 1.27)
				)
			)
		)
		(duplicate_pad_numbers_are_jumpers no)
		(fp_line
			(start 0.7874 -0.4064)
			(end 0.7874 0.4064)
			(stroke
				(width 0.1524)
				(type default)
			)
			(layer "F.SilkS")
		)
		(fp_line
			(start -0.7874 -0.4064)
			(end 0.7874 -0.4064)
			(stroke
				(width 0.1524)
				(type default)
			)
			(layer "F.SilkS")
		)
		(fp_line
			(start 0.7874 0.4064)
			(end -0.7874 0.4064)
			(stroke
				(width 0.1524)
				(type default)
			)
			(layer "F.SilkS")
		)
		(fp_line
			(start -0.7874 0.4064)
			(end -0.7874 -0.4064)
			(stroke
				(width 0.1524)
				(type default)
			)
			(layer "F.SilkS")
		)
		(fp_line
			(start -0.12065 -0.305054)
			(end -0.12065 -0.2794)
			(stroke
				(width 0.1)
				(type default)
			)
			(layer "F.Fab")
		)
		(fp_line
			(start -0.67945 -0.305054)
			(end -0.12065 -0.305054)
			(stroke
				(width 0.1)
				(type default)
			)
			(layer "F.Fab")
		)
		(fp_line
			(start 0.67945 -0.3048)
			(end 0.67945 0.3048)
			(stroke
				(width 0.1)
				(type default)
			)
			(layer "F.Fab")
		)
		(fp_line
			(start 0.12065 -0.3048)
			(end 0.67945 -0.3048)
			(stroke
				(width 0.1)
				(type default)
			)
			(layer "F.Fab")
		)
		(fp_line
			(start 0.12065 -0.2794)
			(end 0.12065 -0.3048)
			(stroke
				(width 0.1)
				(type default)
			)
			(layer "F.Fab")
		)
		(fp_line
			(start -0.12065 -0.2794)
			(end 0.12065 -0.2794)
			(stroke
				(width 0.1)
				(type default)
			)
			(layer "F.Fab")
		)
		(fp_line
			(start 0.120396 0.2794)
			(end -0.12065 0.2794)
			(stroke
				(width 0.1)
				(type default)
			)
			(layer "F.Fab")
		)
		(fp_line
			(start -0.12065 0.2794)
			(end -0.12065 0.3048)
			(stroke
				(width 0.1)
				(type default)
			)
			(layer "F.Fab")
		)
		(fp_line
			(start 0.67945 0.3048)
			(end 0.120396 0.3048)
			(stroke
				(width 0.1)
				(type default)
			)
			(layer "F.Fab")
		)
		(fp_line
			(start 0.120396 0.3048)
			(end 0.120396 0.2794)
			(stroke
				(width 0.1)
				(type default)
			)
			(layer "F.Fab")
		)
		(fp_line
			(start -0.12065 0.3048)
			(end -0.67945 0.3048)
			(stroke
				(width 0.1)
				(type default)
			)
			(layer "F.Fab")
		)
		(fp_line
			(start -0.67945 0.3048)
			(end -0.67945 -0.305054)
			(stroke
				(width 0.1)
				(type default)
			)
			(layer "F.Fab")
		)
		(pad "1" smd circle
			(at -0.40005 0 90)
			(size 0 0)
			(layers "F.Cu" "F.Mask" "F.Paste")
			(net "P3V3_SSD12_CO_DV_DT")
		)
		(pad "2" smd circle
			(at 0.40005 0 90)
			(size 0 0)
			(layers "F.Cu" "F.Mask" "F.Paste")
			(net "GND")
		)
	)
)
